# S9S_MB_2U (Grand Teton) — schematic netlist excerpt (pin names and nets, part order shuffled) for the footprints in the layout excerpt that follows; sources: Cadence DE-HDL packaged netlist, KiCad conversion of 03242023_DA0F0TMBIJ0_F0T_Motherboard_J_brd_V01_OCP.brd

R442  Q_RES  1 1% CHIP  pkg 0603LF  page 210 : A = P3V3_AUX_CLK_GEN_VDDXTAL_CK440 ; B = P3V3_AUX_CLK_GEN_VDDA25M_CK440
C1255  Q_CAP  10UF 6.3V 20% X6S  pkg C0603  page 189 : A = P1V8_PCH_PLL_AUX ; B = GND

(kicad_pcb
	(version 20260206)
	(generator "pcbnew")
	(generator_version "10.0")
	(general
		(thickness 1.6)
		(legacy_teardrops no)
	)
	(paper "A4")
	(title_block
		(title "03242023_DA0F0TMBIJ0_F0T_Motherboard_J_brd_V01_OCP.brd")
		(comment 1 "Grand Teton / footprints 5891-5892 of 6105")
	)
	(layers
		(0 "F.Cu" signal "TOP")
		(4 "In1.Cu" signal "GND")
		(6 "In2.Cu" signal "IN1")
		(8 "In3.Cu" signal "GND1")
		(10 "In4.Cu" signal "IN2")
		(12 "In5.Cu" signal "GND2")
		(14 "In6.Cu" signal "IN3")
		(16 "In7.Cu" signal "GND3")
		(18 "In8.Cu" signal "VCC")
		(20 "In9.Cu" signal "VCC1")
		(22 "In10.Cu" signal "GND4")
		(24 "In11.Cu" signal "IN4")
		(26 "In12.Cu" signal "GND5")
		(28 "In13.Cu" signal "IN5")
		(30 "In14.Cu" signal "GND6")
		(32 "In15.Cu" signal "IN6")
		(34 "In16.Cu" signal "GND7")
		(2 "B.Cu" signal "BOTTOM")
		(9 "F.Adhes" user "F.Adhesive")
		(11 "B.Adhes" user "B.Adhesive")
		(13 "F.Paste" user "Package Geometry/Pastemask Top")
		(15 "B.Paste" user "Package Geometry/Pastemask Bottom")
		(5 "F.SilkS" user "Ref Des/Silkscreen Top")
		(7 "B.SilkS" user "Ref Des/Silkscreen Bottom")
		(1 "F.Mask" user "Board Geometry/Soldermask Top")
		(3 "B.Mask" user "Board Geometry/Soldermask Bottom")
		(17 "Dwgs.User" user "User.Drawings")
		(19 "Cmts.User" user "User.Comments")
		(21 "Eco1.User" user "User.Eco1")
		(23 "Eco2.User" user "User.Eco2")
		(25 "Edge.Cuts" user "Board Geometry/Outline")
		(27 "Margin" user)
		(31 "F.CrtYd" user "Package Geometry/Place Bound Top")
		(29 "B.CrtYd" user "Package Geometry/Place Bound Bottom")
		(35 "F.Fab" user "Ref Des/Assembly Top")
		(33 "B.Fab" user "Ref Des/Assembly Bottom")
	)
	(footprint ""
		(layer "B.Cu")
		(at 347.398594 -54.484016 90)
		(property "Reference" "C1255"
			(at 0 0 90)
			(layer "B.SilkS")
			(hide yes)
			(effects
				(font
					(size 1.27 1.27)
				)
				(justify mirror)
			)
		)
		(property "Value" ""
			(at 0 0 90)
			(layer "B.Fab")
			(effects
				(font
					(size 1.27 1.27)
				)
				(justify mirror)
			)
		)
		(duplicate_pad_numbers_are_jumpers no)
		(fp_line
			(start 1.2954 -0.5842)
			(end -1.2954 -0.5842)
			(stroke
				(width 0.1524)
				(type default)
			)
			(layer "B.SilkS")
		)
		(fp_line
			(start 0 -0.5842)
			(end 0 0.5842)
			(stroke
				(width 0.1524)
				(type default)
			)
			(layer "B.SilkS")
		)
		(fp_line
			(start -1.2954 -0.5842)
			(end -1.2954 0.5842)
			(stroke
				(width 0.1524)
				(type default)
			)
			(layer "B.SilkS")
		)
		(fp_line
			(start 1.2954 0.5842)
			(end 1.2954 -0.5842)
			(stroke
				(width 0.1524)
				(type default)
			)
			(layer "B.SilkS")
		)
		(fp_line
			(start -1.2954 0.5842)
			(end 1.2954 0.5842)
			(stroke
				(width 0.1524)
				(type default)
			)
			(layer "B.SilkS")
		)
		(fp_line
			(start 0.8636 -0.4572)
			(end -0.8636 -0.4572)
			(stroke
				(width 0.1)
				(type default)
			)
			(layer "B.Fab")
		)
		(fp_line
			(start -0.8636 -0.4572)
			(end -0.8636 -0.4064)
			(stroke
				(width 0.1)
				(type default)
			)
			(layer "B.Fab")
		)
		(fp_line
			(start 1.1938 -0.4064)
			(end 0.8636 -0.4064)
			(stroke
				(width 0.1)
				(type default)
			)
			(layer "B.Fab")
		)
		(fp_line
			(start 0.8636 -0.4064)
			(end 0.8636 -0.4572)
			(stroke
				(width 0.1)
				(type default)
			)
			(layer "B.Fab")
		)
		(fp_line
			(start -0.8636 -0.4064)
			(end -1.1938 -0.4064)
			(stroke
				(width 0.1)
				(type default)
			)
			(layer "B.Fab")
		)
		(fp_line
			(start -1.1938 -0.4064)
			(end -1.1938 0.4064)
			(stroke
				(width 0.1)
				(type default)
			)
			(layer "B.Fab")
		)
		(fp_line
			(start 1.1938 0.4064)
			(end 1.1938 -0.4064)
			(stroke
				(width 0.1)
				(type default)
			)
			(layer "B.Fab")
		)
		(fp_line
			(start 0.8636 0.4064)
			(end 1.1938 0.4064)
			(stroke
				(width 0.1)
				(type default)
			)
			(layer "B.Fab")
		)
		(fp_line
			(start -0.8636 0.4064)
			(end -0.8636 0.4572)
			(stroke
				(width 0.1)
				(type default)
			)
			(layer "B.Fab")
		)
		(fp_line
			(start -1.1938 0.4064)
			(end -0.8636 0.4064)
			(stroke
				(width 0.1)
				(type default)
			)
			(layer "B.Fab")
		)
		(fp_line
			(start 0.8636 0.4572)
			(end 0.8636 0.4064)
			(stroke
				(width 0.1)
				(type default)
			)
			(layer "B.Fab")
		)
		(fp_line
			(start -0.8636 0.4572)
			(end 0.8636 0.4572)
			(stroke
				(width 0.1)
				(type default)
			)
			(layer "B.Fab")
		)
		(pad "1" smd rect
			(at 0.7366 0)
			(size 0.7112 0.8128)
			(layers "B.Cu" "B.Mask" "B.Paste")
			(net "P1V8_PCH_PLL_AUX")
		)
		(pad "2" smd rect
			(at -0.7366 0)
			(size 0.7112 0.8128)
			(layers "B.Cu" "B.Mask" "B.Paste")
			(net "GND")
		)
	)
	(footprint ""
		(layer "B.Cu")
		(at 241.786156 -97.551748 -90)
		(property "Reference" "R442"
			(at 0 0 90)
			(layer "B.SilkS")
			(hide yes)
			(effects
				(font
					(size 1.27 1.27)
				)
				(justify mirror)
			)
		)
		(property "Value" ""
			(at 0 0 90)
			(layer "B.Fab")
			(effects
				(font
					(size 1.27 1.27)
				)
				(justify mirror)
			)
		)
		(duplicate_pad_numbers_are_jumpers no)
		(fp_line
			(start -1.2954 0.5842)
			(end 1.2954 0.5842)
			(stroke
				(width 0.1524)
				(type default)
			)
			(layer "B.SilkS")
		)
		(fp_line
			(start 1.2954 0.5842)
			(end 1.2954 -0.5842)
			(stroke
				(width 0.1524)
				(type default)
			)
			(layer "B.SilkS")
		)
		(fp_line
			(start -1.2954 -0.5842)
			(end -1.2954 0.5842)
			(stroke
				(width 0.1524)
				(type default)
			)
			(layer "B.SilkS")
		)
		(fp_line
			(start 1.2954 -0.5842)
			(end -1.2954 -0.5842)
			(stroke
				(width 0.1524)
				(type default)
			)
			(layer "B.SilkS")
		)
		(fp_line
			(start -0.8636 0.4572)
			(end 0.8636 0.4572)
			(stroke
				(width 0.1)
				(type default)
			)
			(layer "B.Fab")
		)
		(fp_line
			(start 0.8636 0.4572)
			(end 0.8636 0.4318)
			(stroke
				(width 0.1)
				(type default)
			)
			(layer "B.Fab")
		)
		(fp_line
			(start 0.8636 0.4318)
			(end 0.8636 0.4064)
			(stroke
				(width 0.1)
				(type default)
			)
			(layer "B.Fab")
		)
		(fp_line
			(start -1.1938 0.4064)
			(end -0.8636 0.4064)
			(stroke
				(width 0.1)
				(type default)
			)
			(layer "B.Fab")
		)
		(fp_line
			(start -0.8636 0.4064)
			(end -0.8636 0.4572)
			(stroke
				(width 0.1)
				(type default)
			)
			(layer "B.Fab")
		)
		(fp_line
			(start 0.8636 0.4064)
			(end 1.1938 0.4064)
			(stroke
				(width 0.1)
				(type default)
			)
			(layer "B.Fab")
		)
		(fp_line
			(start 1.1938 0.4064)
			(end 1.1938 -0.406654)
			(stroke
				(width 0.1)
				(type default)
			)
			(layer "B.Fab")
		)
		(fp_line
			(start -1.1938 -0.406654)
			(end -1.1938 0.4064)
			(stroke
				(width 0.1)
				(type default)
			)
			(layer "B.Fab")
		)
		(fp_line
			(start -0.8636 -0.406654)
			(end -1.1938 -0.406654)
			(stroke
				(width 0.1)
				(type default)
			)
			(layer "B.Fab")
		)
		(fp_line
			(start 0.8636 -0.406654)
			(end 0.8636 -0.4572)
			(stroke
				(width 0.1)
				(type default)
			)
			(layer "B.Fab")
		)
		(fp_line
			(start 1.1938 -0.406654)
			(end 0.8636 -0.406654)
			(stroke
				(width 0.1)
				(type default)
			)
			(layer "B.Fab")
		)
		(fp_line
			(start -0.8636 -0.4572)
			(end -0.8636 -0.406654)
			(stroke
				(width 0.1)
				(type default)
			)
			(layer "B.Fab")
		)
		(fp_line
			(start 0.8636 -0.4572)
			(end -0.8636 -0.4572)
			(stroke
				(width 0.1)
				(type default)
			)
			(layer "B.Fab")
		)
		(pad "1" smd rect
			(at 0.7366 0 180)
			(size 0.7112 0.8128)
			(layers "B.Cu" "B.Mask" "B.Paste")
			(net "P3V3_AUX_CLK_GEN_VDDXTAL_CK440")
		)
		(pad "2" smd rect
			(at -0.7366 0 180)
			(size 0.7112 0.8128)
			(layers "B.Cu" "B.Mask" "B.Paste")
			(net "P3V3_AUX_CLK_GEN_VDDA25M_CK440")
		)
	)
)
